# T6G (Grand Teton) — schematic netlist excerpt (pin names and nets, part order shuffled) for the footprints in the layout excerpt that follows; sources: Cadence DE-HDL packaged netlist, KiCad conversion of 04192023_DAF0TMB3IC0_F0TG_MB_C_brd_V02_OCP.brd

C2278  Q_CAP  22UF 4V 20% X6S  pkg C0402  page 72 : A = PVDDIO_P1 ; B = GND
R6802  Q_RES  10K 1% CHIP  pkg 0402LF  page 182 : A = FM_9ZXL045_P0_3_OE_N ; B = GND

(kicad_pcb
	(version 20260206)
	(generator "pcbnew")
	(generator_version "10.0")
	(general
		(thickness 1.6)
		(legacy_teardrops no)
	)
	(paper "A4")
	(title_block
		(title "04192023_DAF0TMB3IC0_F0TG_MB_C_brd_V02_OCP.brd")
		(comment 1 "Grand Teton / footprints 2754-2755 of 8354")
	)
	(layers
		(0 "F.Cu" signal "TOP")
		(4 "In1.Cu" signal "GND")
		(6 "In2.Cu" signal "IN1")
		(8 "In3.Cu" signal "GND1")
		(10 "In4.Cu" signal "IN2")
		(12 "In5.Cu" signal "GND2")
		(14 "In6.Cu" signal "IN3")
		(16 "In7.Cu" signal "GND3")
		(18 "In8.Cu" signal "VCC")
		(20 "In9.Cu" signal "VCC1")
		(22 "In10.Cu" signal "GND4")
		(24 "In11.Cu" signal "IN4")
		(26 "In12.Cu" signal "GND5")
		(28 "In13.Cu" signal "IN5")
		(30 "In14.Cu" signal "GND6")
		(32 "In15.Cu" signal "IN6")
		(34 "In16.Cu" signal "GND7")
		(2 "B.Cu" signal "BOTTOM")
		(9 "F.Adhes" user "F.Adhesive")
		(11 "B.Adhes" user "B.Adhesive")
		(13 "F.Paste" user "Package Geometry/Pastemask Top")
		(15 "B.Paste" user "Package Geometry/Pastemask Bottom")
		(5 "F.SilkS" user "Ref Des/Silkscreen Top")
		(7 "B.SilkS" user "Ref Des/Silkscreen Bottom")
		(1 "F.Mask" user "Board Geometry/Soldermask Top")
		(3 "B.Mask" user "Board Geometry/Soldermask Bottom")
		(17 "Dwgs.User" user "User.Drawings")
		(19 "Cmts.User" user "User.Comments")
		(21 "Eco1.User" user "User.Eco1")
		(23 "Eco2.User" user "User.Eco2")
		(25 "Edge.Cuts" user "Board Geometry/Outline")
		(27 "Margin" user)
		(31 "F.CrtYd" user "Package Geometry/Place Bound Top")
		(29 "B.CrtYd" user "Package Geometry/Place Bound Bottom")
		(35 "F.Fab" user "Ref Des/Assembly Top")
		(33 "B.Fab" user "Ref Des/Assembly Bottom")
	)
	(footprint ""
		(layer "F.Cu")
		(at 289.589718 -423.456608 90)
		(property "Reference" "R6802"
			(at 0 0 90)
			(layer "F.SilkS")
			(hide yes)
			(effects
				(font
					(size 1.27 1.27)
				)
			)
		)
		(property "Value" ""
			(at 0 0 90)
			(layer "F.Fab")
			(effects
				(font
					(size 1.27 1.27)
				)
			)
		)
		(duplicate_pad_numbers_are_jumpers no)
		(fp_line
			(start 0.7874 -0.4064)
			(end 0.7874 0.4064)
			(stroke
				(width 0.1524)
				(type default)
			)
			(layer "F.SilkS")
		)
		(fp_line
			(start -0.7874 -0.4064)
			(end 0.7874 -0.4064)
			(stroke
				(width 0.1524)
				(type default)
			)
			(layer "F.SilkS")
		)
		(fp_line
			(start 0.7874 0.4064)
			(end -0.7874 0.4064)
			(stroke
				(width 0.1524)
				(type default)
			)
			(layer "F.SilkS")
		)
		(fp_line
			(start -0.7874 0.4064)
			(end -0.7874 -0.4064)
			(stroke
				(width 0.1524)
				(type default)
			)
			(layer "F.SilkS")
		)
		(fp_line
			(start -0.12065 -0.305054)
			(end -0.12065 -0.2794)
			(stroke
				(width 0.1)
				(type default)
			)
			(layer "F.Fab")
		)
		(fp_line
			(start -0.67945 -0.305054)
			(end -0.12065 -0.305054)
			(stroke
				(width 0.1)
				(type default)
			)
			(layer "F.Fab")
		)
		(fp_line
			(start 0.67945 -0.3048)
			(end 0.67945 0.3048)
			(stroke
				(width 0.1)
				(type default)
			)
			(layer "F.Fab")
		)
		(fp_line
			(start 0.12065 -0.3048)
			(end 0.67945 -0.3048)
			(stroke
				(width 0.1)
				(type default)
			)
			(layer "F.Fab")
		)
		(fp_line
			(start 0.12065 -0.2794)
			(end 0.12065 -0.3048)
			(stroke
				(width 0.1)
				(type default)
			)
			(layer "F.Fab")
		)
		(fp_line
			(start -0.12065 -0.2794)
			(end 0.12065 -0.2794)
			(stroke
				(width 0.1)
				(type default)
			)
			(layer "F.Fab")
		)
		(fp_line
			(start 0.120396 0.2794)
			(end -0.12065 0.2794)
			(stroke
				(width 0.1)
				(type default)
			)
			(layer "F.Fab")
		)
		(fp_line
			(start -0.12065 0.2794)
			(end -0.12065 0.3048)
			(stroke
				(width 0.1)
				(type default)
			)
			(layer "F.Fab")
		)
		(fp_line
			(start 0.67945 0.3048)
			(end 0.120396 0.3048)
			(stroke
				(width 0.1)
				(type default)
			)
			(layer "F.Fab")
		)
		(fp_line
			(start 0.120396 0.3048)
			(end 0.120396 0.2794)
			(stroke
				(width 0.1)
				(type default)
			)
			(layer "F.Fab")
		)
		(fp_line
			(start -0.12065 0.3048)
			(end -0.67945 0.3048)
			(stroke
				(width 0.1)
				(type default)
			)
			(layer "F.Fab")
		)
		(fp_line
			(start -0.67945 0.3048)
			(end -0.67945 -0.305054)
			(stroke
				(width 0.1)
				(type default)
			)
			(layer "F.Fab")
		)
		(pad "1" smd circle
			(at -0.40005 0 90)
			(size 0 0)
			(layers "F.Cu" "F.Mask" "F.Paste")
			(net "FM_9ZXL045_P0_3_OE_N")
		)
		(pad "2" smd circle
			(at 0.40005 0 90)
			(size 0 0)
			(layers "F.Cu" "F.Mask" "F.Paste")
			(net "GND")
		)
	)
	(footprint ""
		(layer "F.Cu")
		(at 105.960164 -259.355336)
		(property "Reference" "C2278"
			(at 0 0 0)
			(layer "F.SilkS")
			(hide yes)
			(effects
				(font
					(size 1.27 1.27)
				)
			)
		)
		(property "Value" ""
			(at 0 0 0)
			(layer "F.Fab")
			(effects
				(font
					(size 1.27 1.27)
				)
			)
		)
		(duplicate_pad_numbers_are_jumpers no)
		(fp_line
			(start -0.7874 -0.4064)
			(end 0.7874 -0.4064)
			(stroke
				(width 0.1524)
				(type default)
			)
			(layer "F.SilkS")
		)
		(fp_line
			(start -0.7874 0.4064)
			(end -0.7874 -0.4064)
			(stroke
				(width 0.1524)
				(type default)
			)
			(layer "F.SilkS")
		)
		(fp_line
			(start 0.7874 -0.4064)
			(end 0.7874 0.4064)
			(stroke
				(width 0.1524)
				(type default)
			)
			(layer "F.SilkS")
		)
		(fp_line
			(start 0.7874 0.4064)
			(end -0.7874 0.4064)
			(stroke
				(width 0.1524)
				(type default)
			)
			(layer "F.SilkS")
		)
		(fp_line
			(start -0.67945 -0.305054)
			(end -0.12065 -0.305054)
			(stroke
				(width 0.1)
				(type default)
			)
			(layer "F.Fab")
		)
		(fp_line
			(start -0.67945 0.3048)
			(end -0.67945 -0.305054)
			(stroke
				(width 0.1)
				(type default)
			)
			(layer "F.Fab")
		)
		(fp_line
			(start -0.12065 -0.305054)
			(end -0.12065 -0.2794)
			(stroke
				(width 0.1)
				(type default)
			)
			(layer "F.Fab")
		)
		(fp_line
			(start -0.12065 -0.2794)
			(end 0.12065 -0.2794)
			(stroke
				(width 0.1)
				(type default)
			)
			(layer "F.Fab")
		)
		(fp_line
			(start -0.12065 0.2794)
			(end -0.12065 0.3048)
			(stroke
				(width 0.1)
				(type default)
			)
			(layer "F.Fab")
		)
		(fp_line
			(start -0.12065 0.3048)
			(end -0.67945 0.3048)
			(stroke
				(width 0.1)
				(type default)
			)
			(layer "F.Fab")
		)
		(fp_line
			(start 0.120396 0.2794)
			(end -0.12065 0.2794)
			(stroke
				(width 0.1)
				(type default)
			)
			(layer "F.Fab")
		)
		(fp_line
			(start 0.120396 0.3048)
			(end 0.120396 0.2794)
			(stroke
				(width 0.1)
				(type default)
			)
			(layer "F.Fab")
		)
		(fp_line
			(start 0.12065 -0.3048)
			(end 0.67945 -0.3048)
			(stroke
				(width 0.1)
				(type default)
			)
			(layer "F.Fab")
		)
		(fp_line
			(start 0.12065 -0.2794)
			(end 0.12065 -0.3048)
			(stroke
				(width 0.1)
				(type default)
			)
			(layer "F.Fab")
		)
		(fp_line
			(start 0.67945 -0.3048)
			(end 0.67945 0.3048)
			(stroke
				(width 0.1)
				(type default)
			)
			(layer "F.Fab")
		)
		(fp_line
			(start 0.67945 0.3048)
			(end 0.120396 0.3048)
			(stroke
				(width 0.1)
				(type default)
			)
			(layer "F.Fab")
		)
		(pad "1" smd circle
			(at -0.40005 0)
			(size 0 0)
			(layers "F.Cu" "F.Mask" "F.Paste")
			(net "PVDDIO_P1")
		)
		(pad "2" smd circle
			(at 0.40005 0)
			(size 0 0)
			(layers "F.Cu" "F.Mask" "F.Paste")
			(net "GND")
		)
	)
)
